(kicad_pcb
	(version 20221018)
	(generator pcbnew)
	(general
    (thickness 1.562)
  )
	(paper "A4")
	(title_block
    (title "Thunderbolt PCIe Adaper")
    (date "2024-07-09")
    (rev "1.0.3")
    (comment 1 "www.antmicro.com")
    (comment 2 "Antmicro Ltd.")
		(comment 9 "footprints 211-218 of 271")
	)
	(layers
    (0 "F.Cu" signal)
    (1 "In1.Cu" signal)
    (2 "In2.Cu" signal)
    (3 "In3.Cu" signal)
    (4 "In4.Cu" signal)
    (31 "B.Cu" signal)
    (32 "B.Adhes" user "B.Adhesive")
    (33 "F.Adhes" user "F.Adhesive")
    (34 "B.Paste" user)
    (35 "F.Paste" user)
    (36 "B.SilkS" user "B.Silkscreen")
    (37 "F.SilkS" user "F.Silkscreen")
    (38 "B.Mask" user)
    (39 "F.Mask" user)
    (40 "Dwgs.User" user "User.Drawings")
    (41 "Cmts.User" user "User.Comments")
    (42 "Eco1.User" user "User.Eco1")
    (43 "Eco2.User" user "User.Eco2")
    (44 "Edge.Cuts" user)
    (45 "Margin" user)
    (46 "B.CrtYd" user "B.Courtyard")
    (47 "F.CrtYd" user "F.Courtyard")
    (48 "B.Fab" user)
    (49 "F.Fab" user)
  )
	(footprint "antmicro-footprints:C_0402_1005Metric" (layer "B.Cu")
    (at 139.38 61.03 90)
    (descr "Capacitor SMD 0402")
    (tags "capacitor SMD 0402")
    (property "Author" "Antmicro")
    (property "Dielectric" "X5R")
    (property "License" "Apache-2.0")
    (property "MPN" "GRM155R61H104KE14D")
    (property "Manufacturer" "Murata")
    (property "Sheetfile" "tb.kicad_sch")
    (property "Sheetname" "TB Controller")
    (property "Val" "100n")
    (property "Voltage" "50V")
    (property "ki_description" "SMD Multilayer Ceramic Capacitor, 0.1 µF, 50 V, 0402 [1005 Metric], ± 10%, X5R, GRM Series")
    (property "ki_keywords" "0402, SMT, CAPACITOR, PASSIVE, CERAMIC, MLCC")
    (attr smd)
    (fp_text reference "C98" (at 1.086 -0.569 270) (layer "B.SilkS")
        (effects (font (size 0.7 0.7) (thickness 0.15)) (justify left bottom mirror))
    )
    (fp_text value "C_100n_0402" (at -1.022927 -2.155213 270) (layer "B.Fab")
        (effects (font (size 0.7 0.7) (thickness 0.15)) (justify left bottom mirror))
    )
    (fp_text user "License: Apache-2.0" (at -0.939 -5.799 270) (layer "B.Fab") hide
        (effects (font (size 0.7 0.7) (thickness 0.15)) (justify left bottom mirror))
    )
    (fp_text user "Author: Antmicro" (at -0.939 -3.399 270) (layer "B.Fab") hide
        (effects (font (size 0.7 0.7) (thickness 0.15)) (justify left bottom mirror))
    )
    (fp_text user "${REFERENCE}" (at -0.939 -4.599 270) (layer "B.Fab") hide
        (effects (font (size 0.7 0.7) (thickness 0.15)) (justify left bottom mirror))
    )
    (fp_rect (start -0.925 0.47) (end 0.925 -0.47)
      (stroke (width 0.05) (type default)) (fill none) (layer "B.CrtYd"))
    (fp_line (start -0.494 -0.248) (end -0.494 0.25)
      (stroke (width 0.15) (type solid)) (layer "B.Fab"))
    (fp_line (start -0.494 0.25) (end 0.504 0.25)
      (stroke (width 0.15) (type solid)) (layer "B.Fab"))
    (fp_line (start 0.504 -0.248) (end -0.494 -0.248)
      (stroke (width 0.15) (type solid)) (layer "B.Fab"))
    (fp_line (start 0.504 0.25) (end 0.504 -0.248)
      (stroke (width 0.15) (type solid)) (layer "B.Fab"))
    (pad "1" smd roundrect (at -0.48 0 90) (size 0.59 0.64) (layers "B.Cu" "B.Paste" "B.Mask") (roundrect_rratio 0.25)
      (net 1 "GND") (pintype "passive"))
    (pad "2" smd roundrect (at 0.48 0 90) (size 0.59 0.64) (layers "B.Cu" "B.Paste" "B.Mask") (roundrect_rratio 0.25)
      (net 2 "3V3_SYS") (pintype "passive"))
  )
	(footprint "antmicro-footprints:C_0402_1005Metric" (layer "B.Cu")
    (at 117.450001 64.675 -90)
    (descr "Capacitor SMD 0402")
    (tags "capacitor SMD 0402")
    (property "Author" "Antmicro")
    (property "Dielectric" "")
    (property "License" "Apache-2.0")
    (property "MPN" "CC0402KRX5R6BB224")
    (property "Manufacturer" "YAGEO")
    (property "Sheetfile" "power.kicad_sch")
    (property "Sheetname" "Power")
    (property "Val" "220n")
    (property "Voltage" "")
    (property "ki_description" "SMD Multilayer Ceramic Capacitor, 0.22 µF, 10 V, 0402 [1005 Metric], ± 10%, X5R, CC Series")
    (property "ki_keywords" "0402, SMT, CAPACITOR, PASSIVE, MLCC, CERAMIC")
    (attr smd)
    (fp_text reference "C27" (at 0.984 -0.405999 90) (layer "B.SilkS")
        (effects (font (size 0.7 0.7) (thickness 0.15)) (justify left bottom mirror))
    )
    (fp_text value "C_220n_0402" (at -1.022927 -2.155213 90) (layer "B.Fab")
        (effects (font (size 0.7 0.7) (thickness 0.15)) (justify left bottom mirror))
    )
    (fp_text user "Author: Antmicro" (at -0.939 -3.399 90) (layer "B.Fab") hide
        (effects (font (size 0.7 0.7) (thickness 0.15)) (justify left bottom mirror))
    )
    (fp_text user "${REFERENCE}" (at -0.939 -4.599 90) (layer "B.Fab") hide
        (effects (font (size 0.7 0.7) (thickness 0.15)) (justify left bottom mirror))
    )
    (fp_text user "License: Apache-2.0" (at -0.939 -5.799 90) (layer "B.Fab") hide
        (effects (font (size 0.7 0.7) (thickness 0.15)) (justify left bottom mirror))
    )
    (fp_rect (start -0.925 0.47) (end 0.925 -0.47)
      (stroke (width 0.05) (type default)) (fill none) (layer "B.CrtYd"))
    (fp_line (start -0.494 -0.248) (end -0.494 0.25)
      (stroke (width 0.15) (type solid)) (layer "B.Fab"))
    (fp_line (start -0.494 0.25) (end 0.504 0.25)
      (stroke (width 0.15) (type solid)) (layer "B.Fab"))
    (fp_line (start 0.504 -0.248) (end -0.494 -0.248)
      (stroke (width 0.15) (type solid)) (layer "B.Fab"))
    (fp_line (start 0.504 0.25) (end 0.504 -0.248)
      (stroke (width 0.15) (type solid)) (layer "B.Fab"))
    (pad "1" smd roundrect (at -0.48 0 270) (size 0.59 0.64) (layers "B.Cu" "B.Paste" "B.Mask") (roundrect_rratio 0.25)
      (net 94 "Net-(U2-BST)") (pintype "passive"))
    (pad "2" smd roundrect (at 0.48 0 270) (size 0.59 0.64) (layers "B.Cu" "B.Paste" "B.Mask") (roundrect_rratio 0.25)
      (net 95 "Net-(U2-SW)") (pintype "passive"))
  )
	(footprint "antmicro-footprints:R_0603_1608Metric" (layer "B.Cu")
    (at 113.7175 91.1675 -90)
    (descr "Resistor SMD 0603")
    (tags "resistor SMD 0603")
    (property "Author" "Antmicro")
    (property "License" "Apache-2.0")
    (property "MPN" "PMR03EZPJ000")
    (property "Manufacturer" "ROHM Semiconductor")
    (property "Max. Curr." "22.4A")
    (property "Sheetfile" "power.kicad_sch")
    (property "Sheetname" "Power")
    (property "Tolerance" "template_tolerance")
    (property "Val" "0R")
    (property "ki_description" "SMD Chip Resistor")
    (property "ki_keywords" "0603, SMT, RESISTOR, PASSIVE")
    (attr smd)
    (fp_text reference "R99" (at -4.1725 -1.9795 90) (layer "B.SilkS")
        (effects (font (size 0.7 0.7) (thickness 0.15)) (justify left bottom mirror))
    )
    (fp_text value "R_0R_22.4A_0603" (at 0 -1.6 90) (layer "B.Fab")
        (effects (font (size 0.7 0.7) (thickness 0.15)) (justify left bottom mirror))
    )
    (fp_text user "Author: Antmicro" (at -1.25 -4.9 90) (layer "B.Fab") hide
        (effects (font (size 0.7 0.7) (thickness 0.15)) (justify left bottom mirror))
    )
    (fp_text user "${REFERENCE}" (at -1.25 -3.898 90) (layer "B.Fab") hide
        (effects (font (size 0.7 0.7) (thickness 0.15)) (justify left bottom mirror))
    )
    (fp_text user "License: Apache-2.0" (at -1.25 -5.9 90) (layer "B.Fab") hide
        (effects (font (size 0.7 0.7) (thickness 0.15)) (justify left bottom mirror))
    )
    (fp_line (start -0.15 -0.4) (end 0.15 -0.4)
      (stroke (width 0.15) (type solid)) (layer "B.SilkS"))
    (fp_line (start -0.15 0.4) (end 0.15 0.4)
      (stroke (width 0.15) (type solid)) (layer "B.SilkS"))
    (fp_rect (start -1.25 0.65) (end 1.25 -0.65)
      (stroke (width 0.05) (type solid)) (fill none) (layer "B.CrtYd"))
    (fp_rect (start -0.8 0.4) (end 0.8 -0.4)
      (stroke (width 0.15) (type solid)) (fill none) (layer "B.Fab"))
    (pad "1" smd roundrect (at -0.7 0 270) (size 0.8 1) (layers "B.Cu" "B.Paste" "B.Mask") (roundrect_rratio 0.2)
      (net 146 "Net-(Q4-S)") (pintype "passive"))
    (pad "2" smd roundrect (at 0.7 0 270) (size 0.8 1) (layers "B.Cu" "B.Paste" "B.Mask") (roundrect_rratio 0.2)
      (net 8 "12V0_PCIE") (pintype "passive"))
  )
	(footprint "antmicro-footprints:C_0402_1005Metric" (layer "B.Cu")
    (at 115.440001 65.615 90)
    (descr "Capacitor SMD 0402")
    (tags "capacitor SMD 0402")
    (property "Author" "Antmicro")
    (property "Dielectric" "X5R")
    (property "License" "Apache-2.0")
    (property "MPN" "GRM155R61H104KE14D")
    (property "Manufacturer" "Murata")
    (property "Sheetfile" "power.kicad_sch")
    (property "Sheetname" "Power")
    (property "Val" "100n")
    (property "Voltage" "50V")
    (property "ki_description" "SMD Multilayer Ceramic Capacitor, 0.1 µF, 50 V, 0402 [1005 Metric], ± 10%, X5R, GRM Series")
    (property "ki_keywords" "0402, SMT, CAPACITOR, PASSIVE, CERAMIC, MLCC")
    (attr smd)
    (fp_text reference "C24" (at -0.933 0.383999 270) (layer "B.SilkS")
        (effects (font (size 0.7 0.7) (thickness 0.15)) (justify left bottom mirror))
    )
    (fp_text value "C_100n_0402" (at -1.022927 -2.155213 270) (layer "B.Fab")
        (effects (font (size 0.7 0.7) (thickness 0.15)) (justify left bottom mirror))
    )
    (fp_text user "${REFERENCE}" (at -0.939 -4.599 270) (layer "B.Fab") hide
        (effects (font (size 0.7 0.7) (thickness 0.15)) (justify left bottom mirror))
    )
    (fp_text user "License: Apache-2.0" (at -0.939 -5.799 270) (layer "B.Fab") hide
        (effects (font (size 0.7 0.7) (thickness 0.15)) (justify left bottom mirror))
    )
    (fp_text user "Author: Antmicro" (at -0.939 -3.399 270) (layer "B.Fab") hide
        (effects (font (size 0.7 0.7) (thickness 0.15)) (justify left bottom mirror))
    )
    (fp_rect (start -0.925 0.47) (end 0.925 -0.47)
      (stroke (width 0.05) (type default)) (fill none) (layer "B.CrtYd"))
    (fp_line (start -0.494 -0.248) (end -0.494 0.25)
      (stroke (width 0.15) (type solid)) (layer "B.Fab"))
    (fp_line (start -0.494 0.25) (end 0.504 0.25)
      (stroke (width 0.15) (type solid)) (layer "B.Fab"))
    (fp_line (start 0.504 -0.248) (end -0.494 -0.248)
      (stroke (width 0.15) (type solid)) (layer "B.Fab"))
    (fp_line (start 0.504 0.25) (end 0.504 -0.248)
      (stroke (width 0.15) (type solid)) (layer "B.Fab"))
    (pad "1" smd roundrect (at -0.48 0 90) (size 0.59 0.64) (layers "B.Cu" "B.Paste" "B.Mask") (roundrect_rratio 0.25)
      (net 1 "GND") (pintype "passive"))
    (pad "2" smd roundrect (at 0.48 0 90) (size 0.59 0.64) (layers "B.Cu" "B.Paste" "B.Mask") (roundrect_rratio 0.25)
      (net 90 "Net-(U2-VIN)") (pintype "passive"))
  )
	(footprint "antmicro-footprints:R_0402_1005Metric" (layer "B.Cu")
    (at 131.075 68.77 90)
    (descr "Resistor SMD 0402")
    (tags "resistor SMD 0402")
    (property "Author" "Antmicro")
    (property "License" "Apache-2.0")
    (property "MPN" "CR0402-FX-1002GLF")
    (property "Manufacturer" "Bourns")
    (property "Sheetfile" "tb.kicad_sch")
    (property "Sheetname" "TB Controller")
    (property "Tolerance" "1%")
    (property "Val" "10k")
    (property "ki_description" "SMD Chip Resistor, 10 kohm, ± 1%, 62.5 mW, 0402 [1005 Metric], Thick Film, General Purpose")
    (property "ki_keywords" "0402, SMT, RESISTOR, PASSIVE")
    (attr smd)
    (fp_text reference "R80" (at 1.079 -2.678 270) (layer "B.SilkS")
        (effects (font (size 0.7 0.7) (thickness 0.15)) (justify left bottom mirror))
    )
    (fp_text value "R_10k_0402" (at -1.011843 -1.772047 270) (layer "B.Fab")
        (effects (font (size 0.7 0.7) (thickness 0.15)) (justify left bottom mirror))
    )
    (fp_text user "Author: Antmicro" (at -0.95 -4.169 270) (layer "B.Fab") hide
        (effects (font (size 0.7 0.7) (thickness 0.15)) (justify left bottom mirror))
    )
    (fp_text user "${REFERENCE}" (at -0.95 -3.168 270) (layer "B.Fab") hide
        (effects (font (size 0.7 0.7) (thickness 0.15)) (justify left bottom mirror))
    )
    (fp_text user "License: Apache-2.0" (at -0.95 -5.169 270) (layer "B.Fab") hide
        (effects (font (size 0.7 0.7) (thickness 0.15)) (justify left bottom mirror))
    )
    (fp_rect (start -0.925 0.47) (end 0.925 -0.47)
      (stroke (width 0.05) (type default)) (fill none) (layer "B.CrtYd"))
    (fp_rect (start -0.5 0.25) (end 0.5 -0.25)
      (stroke (width 0.15) (type solid)) (fill none) (layer "B.Fab"))
    (pad "1" smd roundrect (at -0.48 0 90) (size 0.59 0.64) (layers "B.Cu" "B.Paste" "B.Mask") (roundrect_rratio 0.25)
      (net 195 "Net-(U4C-GPIO_6)") (pintype "passive"))
    (pad "2" smd roundrect (at 0.48 0 90) (size 0.59 0.64) (layers "B.Cu" "B.Paste" "B.Mask") (roundrect_rratio 0.25)
      (net 1 "GND") (pintype "passive"))
  )
	(footprint "antmicro-footprints:C_0402_1005Metric" (layer "B.Cu")
    (at 161 74.928922)
    (descr "Capacitor SMD 0402")
    (tags "capacitor SMD 0402")
    (property "Author" "Antmicro")
    (property "Dielectric" "X5R")
    (property "License" "Apache-2.0")
    (property "MPN" "GRM155R61H104KE14D")
    (property "Manufacturer" "Murata")
    (property "Sheetfile" "connectors.kicad_sch")
    (property "Sheetname" "Connectors")
    (property "Val" "100n")
    (property "Voltage" "50V")
    (property "ki_description" "SMD Multilayer Ceramic Capacitor, 0.1 µF, 50 V, 0402 [1005 Metric], ± 10%, X5R, GRM Series")
    (property "ki_keywords" "0402, SMT, CAPACITOR, PASSIVE, CERAMIC, MLCC")
    (attr smd)
    (fp_text reference "C2" (at -0.98 0.509078 180) (layer "B.SilkS")
        (effects (font (size 0.7 0.7) (thickness 0.15)) (justify left bottom mirror))
    )
    (fp_text value "C_100n_0402" (at -1.022927 -2.155213 180) (layer "B.Fab")
        (effects (font (size 0.7 0.7) (thickness 0.15)) (justify left bottom mirror))
    )
    (fp_text user "${REFERENCE}" (at -0.939 -4.599 180) (layer "B.Fab") hide
        (effects (font (size 0.7 0.7) (thickness 0.15)) (justify left bottom mirror))
    )
    (fp_text user "Author: Antmicro" (at -0.939 -3.399 180) (layer "B.Fab") hide
        (effects (font (size 0.7 0.7) (thickness 0.15)) (justify left bottom mirror))
    )
    (fp_text user "License: Apache-2.0" (at -0.939 -5.799 180) (layer "B.Fab") hide
        (effects (font (size 0.7 0.7) (thickness 0.15)) (justify left bottom mirror))
    )
    (fp_rect (start -0.925 0.47) (end 0.925 -0.47)
      (stroke (width 0.05) (type default)) (fill none) (layer "B.CrtYd"))
    (fp_line (start -0.494 -0.248) (end -0.494 0.25)
      (stroke (width 0.15) (type solid)) (layer "B.Fab"))
    (fp_line (start -0.494 0.25) (end 0.504 0.25)
      (stroke (width 0.15) (type solid)) (layer "B.Fab"))
    (fp_line (start 0.504 -0.248) (end -0.494 -0.248)
      (stroke (width 0.15) (type solid)) (layer "B.Fab"))
    (fp_line (start 0.504 0.25) (end 0.504 -0.248)
      (stroke (width 0.15) (type solid)) (layer "B.Fab"))
    (pad "1" smd roundrect (at -0.48 0) (size 0.59 0.64) (layers "B.Cu" "B.Paste" "B.Mask") (roundrect_rratio 0.25)
      (net 1 "GND") (pintype "passive"))
    (pad "2" smd roundrect (at 0.48 0) (size 0.59 0.64) (layers "B.Cu" "B.Paste" "B.Mask") (roundrect_rratio 0.25)
      (net 3 "5V0_USB") (pintype "passive"))
  )
	(footprint "antmicro-footprints:R_0402_1005Metric" (layer "B.Cu")
    (at 134.15 66.82 -90)
    (descr "Resistor SMD 0402")
    (tags "resistor SMD 0402")
    (property "Author" "Antmicro")
    (property "License" "Apache-2.0")
    (property "MPN" "CR0402-FX-1002GLF")
    (property "Manufacturer" "Bourns")
    (property "Sheetfile" "tb.kicad_sch")
    (property "Sheetname" "TB Controller")
    (property "Tolerance" "1%")
    (property "Val" "10k")
    (property "ki_description" "SMD Chip Resistor, 10 kohm, ± 1%, 62.5 mW, 0402 [1005 Metric], Thick Film, General Purpose")
    (property "ki_keywords" "0402, SMT, RESISTOR, PASSIVE")
    (attr smd)
    (fp_text reference "R67" (at -3.066 -0.325 90) (layer "B.SilkS")
        (effects (font (size 0.7 0.7) (thickness 0.15)) (justify left bottom mirror))
    )
    (fp_text value "R_10k_0402" (at -1.011843 -1.772047 90) (layer "B.Fab")
        (effects (font (size 0.7 0.7) (thickness 0.15)) (justify left bottom mirror))
    )
    (fp_text user "License: Apache-2.0" (at -0.95 -5.169 90) (layer "B.Fab") hide
        (effects (font (size 0.7 0.7) (thickness 0.15)) (justify left bottom mirror))
    )
    (fp_text user "Author: Antmicro" (at -0.95 -4.169 90) (layer "B.Fab") hide
        (effects (font (size 0.7 0.7) (thickness 0.15)) (justify left bottom mirror))
    )
    (fp_text user "${REFERENCE}" (at -0.95 -3.168 90) (layer "B.Fab") hide
        (effects (font (size 0.7 0.7) (thickness 0.15)) (justify left bottom mirror))
    )
    (fp_rect (start -0.925 0.47) (end 0.925 -0.47)
      (stroke (width 0.05) (type default)) (fill none) (layer "B.CrtYd"))
    (fp_rect (start -0.5 0.25) (end 0.5 -0.25)
      (stroke (width 0.15) (type solid)) (fill none) (layer "B.Fab"))
    (pad "1" smd roundrect (at -0.48 0 270) (size 0.59 0.64) (layers "B.Cu" "B.Paste" "B.Mask") (roundrect_rratio 0.25)
      (net 2 "3V3_SYS") (pintype "passive"))
    (pad "2" smd roundrect (at 0.48 0 270) (size 0.59 0.64) (layers "B.Cu" "B.Paste" "B.Mask") (roundrect_rratio 0.25)
      (net 181 "Net-(U4D-TDO)") (pintype "passive"))
  )
	(footprint "antmicro-footprints:C_0402_1005Metric" (layer "B.Cu")
    (at 127.505 80.34 -90)
    (descr "Capacitor SMD 0402")
    (tags "capacitor SMD 0402")
    (property "Author" "Antmicro")
    (property "Dielectric" "")
    (property "License" "Apache-2.0")
    (property "MPN" "CC0402MRX5R5BB106")
    (property "Manufacturer" "YAGEO")
    (property "Sheetfile" "tb-power.kicad_sch")
    (property "Sheetname" "Thunderbolt Controller - Power")
    (property "Val" "10u")
    (property "Voltage" "")
    (property "ki_description" "SMD Multilayer Ceramic Capacitor, 10 µF, 6.3 V, 0402 [1005 Metric], ± 20%, X5R, CC Series")
    (property "ki_keywords" "0402, SMT, CAPACITOR, PASSIVE, MLCC, CERAMIC")
    (attr smd)
    (fp_text reference "C96" (at -0.965 2.537 90) (layer "B.SilkS")
        (effects (font (size 0.7 0.7) (thickness 0.15)) (justify left bottom mirror))
    )
    (fp_text value "C_10u_0402" (at -1.022927 -2.155213 90) (layer "B.Fab")
        (effects (font (size 0.7 0.7) (thickness 0.15)) (justify left bottom mirror))
    )
    (fp_text user "${REFERENCE}" (at -0.939 -4.599 90) (layer "B.Fab") hide
        (effects (font (size 0.7 0.7) (thickness 0.15)) (justify left bottom mirror))
    )
    (fp_text user "License: Apache-2.0" (at -0.939 -5.799 90) (layer "B.Fab") hide
        (effects (font (size 0.7 0.7) (thickness 0.15)) (justify left bottom mirror))
    )
    (fp_text user "Author: Antmicro" (at -0.939 -3.399 90) (layer "B.Fab") hide
        (effects (font (size 0.7 0.7) (thickness 0.15)) (justify left bottom mirror))
    )
    (fp_rect (start -0.925 0.47) (end 0.925 -0.47)
      (stroke (width 0.05) (type default)) (fill none) (layer "B.CrtYd"))
    (fp_line (start -0.494 -0.248) (end -0.494 0.25)
      (stroke (width 0.15) (type solid)) (layer "B.Fab"))
    (fp_line (start -0.494 0.25) (end 0.504 0.25)
      (stroke (width 0.15) (type solid)) (layer "B.Fab"))
    (fp_line (start 0.504 -0.248) (end -0.494 -0.248)
      (stroke (width 0.15) (type solid)) (layer "B.Fab"))
    (fp_line (start 0.504 0.25) (end 0.504 -0.248)
      (stroke (width 0.15) (type solid)) (layer "B.Fab"))
    (pad "1" smd roundrect (at -0.48 0 270) (size 0.59 0.64) (layers "B.Cu" "B.Paste" "B.Mask") (roundrect_rratio 0.25)
      (net 1 "GND") (pintype "passive"))
    (pad "2" smd roundrect (at 0.48 0 270) (size 0.59 0.64) (layers "B.Cu" "B.Paste" "B.Mask") (roundrect_rratio 0.25)
      (net 114 "Net-(U4A-VCC3P3_S0)") (pintype "passive"))
  )
)
